FILE_TYPE=LIBRARY_PARTS;
primitive 'CONN3_G98259001','CONN3_G98259001_THMT','CONN3_G98259001_PIP';
  pin
    'IO1':
      PIN_NUMBER='(1)';
      BIDIRECTIONAL='TRUE';
      INPUT_LOAD='(-0.01,0.01)';
      OUTPUT_LOAD='(1.0,-1.0)';
    'IO2':
      PIN_NUMBER='(2)';
      BIDIRECTIONAL='TRUE';
      INPUT_LOAD='(-0.01,0.01)';
      OUTPUT_LOAD='(1.0,-1.0)';
    'IO3':
      PIN_NUMBER='(3)';
      BIDIRECTIONAL='TRUE';
      INPUT_LOAD='(-0.01,0.01)';
      OUTPUT_LOAD='(1.0,-1.0)';
  end_pin;
  body
    PART_NAME='CONN3_G98259001';
    PHYS_DES_PREFIX='J';
      end_body;
end_primitive;

END.
